(kicad_pcb
	(version 20260206)
	(generator "pcbnew")
	(generator_version "10.0")
	(general
		(thickness 1.6)
		(legacy_teardrops no)
	)
	(paper "A4")
	(title_block
		(title "baseboard — 13948-1b.1110WZS1818.brd")
		(comment 1 "Honey Badger (Wiwynn) / footprints 266-273 of 2523")
	)
	(layers
		(0 "F.Cu" signal "TOP")
		(4 "In1.Cu" signal "L2GND")
		(6 "In2.Cu" signal "L3")
		(8 "In3.Cu" signal "L4VCC")
		(10 "In4.Cu" signal "L5VCC")
		(12 "In5.Cu" signal "L6")
		(14 "In6.Cu" signal "L7GND")
		(2 "B.Cu" signal "BOTTOM")
		(9 "F.Adhes" user "F.Adhesive")
		(11 "B.Adhes" user "B.Adhesive")
		(13 "F.Paste" user "Package Geometry/Pastemask Top")
		(15 "B.Paste" user "Package Geometry/Pastemask Bottom")
		(5 "F.SilkS" user "Ref Des/Silkscreen Top")
		(7 "B.SilkS" user "Ref Des/Silkscreen Bottom")
		(1 "F.Mask" user "Board Geometry/Soldermask Top")
		(3 "B.Mask" user "Board Geometry/Soldermask Bottom")
		(17 "Dwgs.User" user "User.Drawings")
		(19 "Cmts.User" user "User.Comments")
		(21 "Eco1.User" user "User.Eco1")
		(23 "Eco2.User" user "User.Eco2")
		(25 "Edge.Cuts" user "Board Geometry/Outline")
		(27 "Margin" user)
		(31 "F.CrtYd" user "Package Geometry/Place Bound Top")
		(29 "B.CrtYd" user "Package Geometry/Place Bound Bottom")
		(35 "F.Fab" user "Ref Des/Assembly Top")
		(33 "B.Fab" user "Ref Des/Assembly Bottom")
	)
	(footprint ""
		(layer "F.Cu")
		(at 180.721 -147.828 -90)
		(property "Reference" "SR918"
			(at 0 0 270)
			(layer "F.SilkS")
			(hide yes)
			(effects
				(font
					(size 1.27 1.27)
				)
			)
		)
		(property "Value" "4K7R2F-GP"
			(at 0.064008 -3.993896 270)
			(unlocked yes)
			(layer "F.Fab")
			(hide yes)
			(effects
				(font
					(size 1.016 1.016)
					(thickness 0.1524)
				)
			)
		)
		(property "Device Type" "R402H16"
			(at 0.064008 -5.517896 270)
			(unlocked yes)
			(layer "F.Fab")
			(hide yes)
			(effects
				(font
					(size 1.016 1.016)
					(thickness 0.1524)
				)
			)
		)
		(duplicate_pad_numbers_are_jumpers no)
		(fp_line
			(start -0.508 -0.9398)
			(end -0.508 0.9398)
			(stroke
				(width 0.1524)
				(type default)
			)
			(layer "F.SilkS")
		)
		(fp_line
			(start 0.508 -0.9398)
			(end -0.508 -0.9398)
			(stroke
				(width 0.1524)
				(type default)
			)
			(layer "F.SilkS")
		)
		(fp_rect
			(start -0.508 0.9398)
			(end 0.508 -0.9398)
			(stroke
				(width 0)
				(type default)
			)
			(fill no)
			(layer "F.CrtYd")
		)
		(fp_rect
			(start -0.508 0.9398)
			(end 0.508 -0.9398)
			(stroke
				(width 0)
				(type default)
			)
			(fill no)
			(layer "F.Fab")
		)
		(pad "1" smd custom
			(at 0 -0.4445 270)
			(size 0.1397 0.1397)
			(layers "F.Cu" "F.Mask" "F.Paste")
			(net "BMC_I2C_C_SDA")
			(options
				(clearance outline)
				(anchor circle)
			)
			(primitives
				(gr_poly
					(pts
						(arc
							(start -0.1778 -0.2794)
							(mid -0.249642 -0.249642)
							(end -0.2794 -0.1778)
						)
						(arc
							(start -0.2794 0.1778)
							(mid -0.249642 0.249642)
							(end -0.1778 0.2794)
						)
						(arc
							(start 0.1778 0.2794)
							(mid 0.249642 0.249642)
							(end 0.2794 0.1778)
						)
						(arc
							(start 0.2794 -0.1778)
							(mid 0.249642 -0.249642)
							(end 0.1778 -0.2794)
						)
					)
					(width 0)
					(fill yes)
				)
			)
		)
		(pad "2" smd custom
			(at 0 0.4445 270)
			(size 0.1397 0.1397)
			(layers "F.Cu" "F.Mask" "F.Paste")
			(net "P3V3_STBY")
			(options
				(clearance outline)
				(anchor circle)
			)
			(primitives
				(gr_poly
					(pts
						(arc
							(start -0.1778 -0.2794)
							(mid -0.249642 -0.249642)
							(end -0.2794 -0.1778)
						)
						(arc
							(start -0.2794 0.1778)
							(mid -0.249642 0.249642)
							(end -0.1778 0.2794)
						)
						(arc
							(start 0.1778 0.2794)
							(mid 0.249642 0.249642)
							(end 0.2794 0.1778)
						)
						(arc
							(start 0.2794 -0.1778)
							(mid 0.249642 -0.249642)
							(end 0.1778 -0.2794)
						)
					)
					(width 0)
					(fill yes)
				)
			)
		)
	)
	(footprint ""
		(layer "F.Cu")
		(at 277.994872 -220.290136 90)
		(property "Reference" "PR81"
			(at 0 0 90)
			(layer "F.SilkS")
			(hide yes)
			(effects
				(font
					(size 1.27 1.27)
				)
			)
		)
		(property "Value" "0R2J-2-GP"
			(at 0.064008 -3.993896 90)
			(unlocked yes)
			(layer "F.Fab")
			(hide yes)
			(effects
				(font
					(size 1.016 1.016)
					(thickness 0.1524)
				)
			)
		)
		(property "Device Type" "R402H16"
			(at 0.064008 -5.517896 90)
			(unlocked yes)
			(layer "F.Fab")
			(hide yes)
			(effects
				(font
					(size 1.016 1.016)
					(thickness 0.1524)
				)
			)
		)
		(duplicate_pad_numbers_are_jumpers no)
		(fp_line
			(start 0.508 -0.9398)
			(end -0.508 -0.9398)
			(stroke
				(width 0.1524)
				(type default)
			)
			(layer "F.SilkS")
		)
		(fp_line
			(start -0.508 -0.9398)
			(end -0.508 0.9398)
			(stroke
				(width 0.1524)
				(type default)
			)
			(layer "F.SilkS")
		)
		(fp_rect
			(start -0.508 0.9398)
			(end 0.508 -0.9398)
			(stroke
				(width 0)
				(type default)
			)
			(fill no)
			(layer "F.CrtYd")
		)
		(fp_rect
			(start -0.508 0.9398)
			(end 0.508 -0.9398)
			(stroke
				(width 0)
				(type default)
			)
			(fill no)
			(layer "F.Fab")
		)
		(pad "1" smd custom
			(at 0 -0.4445 90)
			(size 0.1397 0.1397)
			(layers "F.Cu" "F.Mask" "F.Paste")
			(net "P3V3_STBY")
			(options
				(clearance outline)
				(anchor circle)
			)
			(primitives
				(gr_poly
					(pts
						(arc
							(start -0.1778 -0.2794)
							(mid -0.249642 -0.249642)
							(end -0.2794 -0.1778)
						)
						(arc
							(start -0.2794 0.1778)
							(mid -0.249642 0.249642)
							(end -0.1778 0.2794)
						)
						(arc
							(start 0.1778 0.2794)
							(mid 0.249642 0.249642)
							(end 0.2794 0.1778)
						)
						(arc
							(start 0.2794 -0.1778)
							(mid 0.249642 -0.249642)
							(end 0.1778 -0.2794)
						)
					)
					(width 0)
					(fill yes)
				)
			)
		)
		(pad "2" smd custom
			(at 0 0.4445 90)
			(size 0.1397 0.1397)
			(layers "F.Cu" "F.Mask" "F.Paste")
			(net "TPS74801_1V53_STBY_BIAS")
			(options
				(clearance outline)
				(anchor circle)
			)
			(primitives
				(gr_poly
					(pts
						(arc
							(start -0.1778 -0.2794)
							(mid -0.249642 -0.249642)
							(end -0.2794 -0.1778)
						)
						(arc
							(start -0.2794 0.1778)
							(mid -0.249642 0.249642)
							(end -0.1778 0.2794)
						)
						(arc
							(start 0.1778 0.2794)
							(mid 0.249642 0.249642)
							(end 0.2794 0.1778)
						)
						(arc
							(start 0.2794 -0.1778)
							(mid 0.249642 -0.249642)
							(end 0.1778 -0.2794)
						)
					)
					(width 0)
					(fill yes)
				)
			)
		)
	)
	(footprint ""
		(layer "F.Cu")
		(at 120.339612 -221.996 180)
		(property "Reference" "SR876"
			(at 0 0 180)
			(layer "F.SilkS")
			(hide yes)
			(effects
				(font
					(size 1.27 1.27)
				)
			)
		)
		(property "Value" "0R2J-2-GP"
			(at 0.064008 -3.993896 180)
			(unlocked yes)
			(layer "F.Fab")
			(hide yes)
			(effects
				(font
					(size 1.016 1.016)
					(thickness 0.1524)
				)
			)
		)
		(property "Device Type" "R402H16"
			(at 0.064008 -5.517896 180)
			(unlocked yes)
			(layer "F.Fab")
			(hide yes)
			(effects
				(font
					(size 1.016 1.016)
					(thickness 0.1524)
				)
			)
		)
		(duplicate_pad_numbers_are_jumpers no)
		(fp_line
			(start 0.508 -0.9398)
			(end -0.508 -0.9398)
			(stroke
				(width 0.1524)
				(type default)
			)
			(layer "F.SilkS")
		)
		(fp_line
			(start -0.508 -0.9398)
			(end -0.508 0.9398)
			(stroke
				(width 0.1524)
				(type default)
			)
			(layer "F.SilkS")
		)
		(fp_rect
			(start -0.508 0.9398)
			(end 0.508 -0.9398)
			(stroke
				(width 0)
				(type default)
			)
			(fill no)
			(layer "F.CrtYd")
		)
		(fp_rect
			(start -0.508 0.9398)
			(end 0.508 -0.9398)
			(stroke
				(width 0)
				(type default)
			)
			(fill no)
			(layer "F.Fab")
		)
		(pad "1" smd custom
			(at 0 -0.4445 180)
			(size 0.1397 0.1397)
			(layers "F.Cu" "F.Mask" "F.Paste")
			(net "REDV_TX7_N")
			(options
				(clearance outline)
				(anchor circle)
			)
			(primitives
				(gr_poly
					(pts
						(arc
							(start -0.1778 -0.2794)
							(mid -0.249642 -0.249642)
							(end -0.2794 -0.1778)
						)
						(arc
							(start -0.2794 0.1778)
							(mid -0.249642 0.249642)
							(end -0.1778 0.2794)
						)
						(arc
							(start 0.1778 0.2794)
							(mid 0.249642 0.249642)
							(end 0.2794 0.1778)
						)
						(arc
							(start 0.2794 -0.1778)
							(mid 0.249642 -0.249642)
							(end 0.1778 -0.2794)
						)
					)
					(width 0)
					(fill yes)
				)
			)
		)
		(pad "2" smd custom
			(at 0 0.4445 180)
			(size 0.1397 0.1397)
			(layers "F.Cu" "F.Mask" "F.Paste")
			(net "SAS_HDD_CONN_TX7_N")
			(options
				(clearance outline)
				(anchor circle)
			)
			(primitives
				(gr_poly
					(pts
						(arc
							(start -0.1778 -0.2794)
							(mid -0.249642 -0.249642)
							(end -0.2794 -0.1778)
						)
						(arc
							(start -0.2794 0.1778)
							(mid -0.249642 0.249642)
							(end -0.1778 0.2794)
						)
						(arc
							(start 0.1778 0.2794)
							(mid 0.249642 0.249642)
							(end 0.2794 0.1778)
						)
						(arc
							(start 0.2794 -0.1778)
							(mid 0.249642 -0.249642)
							(end 0.1778 -0.2794)
						)
					)
					(width 0)
					(fill yes)
				)
			)
		)
	)
	(footprint ""
		(layer "F.Cu")
		(at 272.288 -41.148)
		(property "Reference" "PC41"
			(at 0 0 0)
			(layer "F.SilkS")
			(hide yes)
			(effects
				(font
					(size 1.27 1.27)
				)
			)
		)
		(property "Value" "SC22U25V5MX-GP"
			(at -0.0762 -6.1214 0)
			(unlocked yes)
			(layer "F.Fab")
			(hide yes)
			(effects
				(font
					(size 1.016 1.016)
					(thickness 0.1524)
				)
			)
		)
		(property "Device Type" "C805H58"
			(at -0.0762 -8.1534 0)
			(unlocked yes)
			(layer "F.Fab")
			(hide yes)
			(effects
				(font
					(size 1.016 1.016)
					(thickness 0.1524)
				)
			)
		)
		(duplicate_pad_numbers_are_jumpers no)
		(fp_line
			(start 0.635 0)
			(end -0.635 0)
			(stroke
				(width 0.508)
				(type default)
			)
			(layer "F.SilkS")
		)
		(fp_rect
			(start -0.9652 1.778)
			(end 0.9652 -1.778)
			(stroke
				(width 0)
				(type default)
			)
			(fill no)
			(layer "F.CrtYd")
		)
		(fp_poly
			(pts
				(xy -0.9652 -1.778) (xy 0.9652 -1.778) (xy 0.9652 1.778) (xy -0.9652 1.778)
			)
			(stroke
				(width 0)
				(type default)
			)
			(fill no)
			(layer "F.Fab")
		)
		(pad "1" smd rect
			(at 0 -0.9652)
			(size 1.397 1.143)
			(layers "F.Cu" "F.Mask" "F.Paste")
			(net "P1V8_STBY_VIN")
		)
		(pad "2" smd rect
			(at 0 0.9652)
			(size 1.397 1.143)
			(layers "F.Cu" "F.Mask" "F.Paste")
			(net "GND")
		)
	)
	(footprint ""
		(layer "F.Cu")
		(at 174.107348 -127.879856 90)
		(property "Reference" "PC174"
			(at 0 0 90)
			(layer "F.SilkS")
			(hide yes)
			(effects
				(font
					(size 1.27 1.27)
				)
			)
		)
		(property "Value" "SC22U25V5MX-GP"
			(at -0.0762 -6.1214 90)
			(unlocked yes)
			(layer "F.Fab")
			(hide yes)
			(effects
				(font
					(size 1.016 1.016)
					(thickness 0.1524)
				)
			)
		)
		(property "Device Type" "C805H58"
			(at -0.0762 -8.1534 90)
			(unlocked yes)
			(layer "F.Fab")
			(hide yes)
			(effects
				(font
					(size 1.016 1.016)
					(thickness 0.1524)
				)
			)
		)
		(duplicate_pad_numbers_are_jumpers no)
		(fp_line
			(start 0.635 0)
			(end -0.635 0)
			(stroke
				(width 0.508)
				(type default)
			)
			(layer "F.SilkS")
		)
		(fp_rect
			(start -0.9652 1.778)
			(end 0.9652 -1.778)
			(stroke
				(width 0)
				(type default)
			)
			(fill no)
			(layer "F.CrtYd")
		)
		(fp_poly
			(pts
				(xy -0.9652 -1.778) (xy 0.9652 -1.778) (xy 0.9652 1.778) (xy -0.9652 1.778)
			)
			(stroke
				(width 0)
				(type default)
			)
			(fill no)
			(layer "F.Fab")
		)
		(pad "1" smd rect
			(at 0 -0.9652 90)
			(size 1.397 1.143)
			(layers "F.Cu" "F.Mask" "F.Paste")
			(net "P0V9_E_VIN")
		)
		(pad "2" smd rect
			(at 0 0.9652 90)
			(size 1.397 1.143)
			(layers "F.Cu" "F.Mask" "F.Paste")
			(net "GND")
		)
	)
	(footprint ""
		(layer "F.Cu")
		(at 312.547 -192.405 90)
		(property "Reference" "R803"
			(at 0 0 90)
			(layer "F.SilkS")
			(hide yes)
			(effects
				(font
					(size 1.27 1.27)
				)
			)
		)
		(property "Value" "4K7R2F-GP"
			(at 0.064008 -3.993896 90)
			(unlocked yes)
			(layer "F.Fab")
			(hide yes)
			(effects
				(font
					(size 1.016 1.016)
					(thickness 0.1524)
				)
			)
		)
		(property "Device Type" "R402H16"
			(at 0.064008 -5.517896 90)
			(unlocked yes)
			(layer "F.Fab")
			(hide yes)
			(effects
				(font
					(size 1.016 1.016)
					(thickness 0.1524)
				)
			)
		)
		(duplicate_pad_numbers_are_jumpers no)
		(fp_line
			(start 0.508 -0.9398)
			(end -0.508 -0.9398)
			(stroke
				(width 0.1524)
				(type default)
			)
			(layer "F.SilkS")
		)
		(fp_line
			(start -0.508 -0.9398)
			(end -0.508 0.9398)
			(stroke
				(width 0.1524)
				(type default)
			)
			(layer "F.SilkS")
		)
		(fp_rect
			(start -0.508 0.9398)
			(end 0.508 -0.9398)
			(stroke
				(width 0)
				(type default)
			)
			(fill no)
			(layer "F.CrtYd")
		)
		(fp_rect
			(start -0.508 0.9398)
			(end 0.508 -0.9398)
			(stroke
				(width 0)
				(type default)
			)
			(fill no)
			(layer "F.Fab")
		)
		(pad "1" smd custom
			(at 0 -0.4445 90)
			(size 0.1397 0.1397)
			(layers "F.Cu" "F.Mask" "F.Paste")
			(net "P3V3_STBY")
			(options
				(clearance outline)
				(anchor circle)
			)
			(primitives
				(gr_poly
					(pts
						(arc
							(start -0.1778 -0.2794)
							(mid -0.249642 -0.249642)
							(end -0.2794 -0.1778)
						)
						(arc
							(start -0.2794 0.1778)
							(mid -0.249642 0.249642)
							(end -0.1778 0.2794)
						)
						(arc
							(start 0.1778 0.2794)
							(mid 0.249642 0.249642)
							(end 0.2794 0.1778)
						)
						(arc
							(start 0.2794 -0.1778)
							(mid 0.249642 -0.249642)
							(end 0.1778 -0.2794)
						)
					)
					(width 0)
					(fill yes)
				)
			)
		)
		(pad "2" smd custom
			(at 0 0.4445 90)
			(size 0.1397 0.1397)
			(layers "F.Cu" "F.Mask" "F.Paste")
			(net "JTAG_BMC_TMS")
			(options
				(clearance outline)
				(anchor circle)
			)
			(primitives
				(gr_poly
					(pts
						(arc
							(start -0.1778 -0.2794)
							(mid -0.249642 -0.249642)
							(end -0.2794 -0.1778)
						)
						(arc
							(start -0.2794 0.1778)
							(mid -0.249642 0.249642)
							(end -0.1778 0.2794)
						)
						(arc
							(start 0.1778 0.2794)
							(mid 0.249642 0.249642)
							(end 0.2794 0.1778)
						)
						(arc
							(start 0.2794 -0.1778)
							(mid 0.249642 -0.249642)
							(end 0.1778 -0.2794)
						)
					)
					(width 0)
					(fill yes)
				)
			)
		)
	)
	(footprint ""
		(layer "F.Cu")
		(at 192.024 -147.701 180)
		(property "Reference" "SC1110"
			(at 0 0 180)
			(layer "F.SilkS")
			(hide yes)
			(effects
				(font
					(size 1.27 1.27)
				)
			)
		)
		(property "Value" "SCD1U16V2KX-3GP"
			(at 1.1811 -2.7051 180)
			(unlocked yes)
			(layer "F.Fab")
			(hide yes)
			(effects
				(font
					(size 1.016 1.016)
					(thickness 0.1524)
				)
			)
		)
		(property "Device Type" "C402H22"
			(at 1.1811 -4.2291 180)
			(unlocked yes)
			(layer "F.Fab")
			(hide yes)
			(effects
				(font
					(size 1.016 1.016)
					(thickness 0.1524)
				)
			)
		)
		(duplicate_pad_numbers_are_jumpers no)
		(fp_rect
			(start -0.4318 0.9525)
			(end 0.4318 -0.9525)
			(stroke
				(width 0)
				(type default)
			)
			(fill no)
			(layer "F.CrtYd")
		)
		(fp_rect
			(start -0.4318 0.9525)
			(end 0.4318 -0.9525)
			(stroke
				(width 0)
				(type default)
			)
			(fill no)
			(layer "F.Fab")
		)
		(pad "1" smd custom
			(at 0 -0.4445 180)
			(size 0.1524 0.1524)
			(layers "F.Cu" "F.Mask" "F.Paste")
			(net "P1V8_E")
			(options
				(clearance outline)
				(anchor circle)
			)
			(primitives
				(gr_poly
					(pts
						(arc
							(start 0.3048 -0.2032)
							(mid 0.275042 -0.275042)
							(end 0.2032 -0.3048)
						)
						(arc
							(start -0.2032 -0.3048)
							(mid -0.275042 -0.275042)
							(end -0.3048 -0.2032)
						)
						(arc
							(start -0.3048 0.2032)
							(mid -0.275042 0.275042)
							(end -0.2032 0.3048)
						)
						(arc
							(start 0.2032 0.3048)
							(mid 0.275042 0.275042)
							(end 0.3048 0.2032)
						)
					)
					(width 0)
					(fill yes)
				)
			)
		)
		(pad "2" smd custom
			(at 0 0.4445 180)
			(size 0.1524 0.1524)
			(layers "F.Cu" "F.Mask" "F.Paste")
			(net "GND")
			(options
				(clearance outline)
				(anchor circle)
			)
			(primitives
				(gr_poly
					(pts
						(arc
							(start 0.3048 -0.2032)
							(mid 0.275042 -0.275042)
							(end 0.2032 -0.3048)
						)
						(arc
							(start -0.2032 -0.3048)
							(mid -0.275042 -0.275042)
							(end -0.3048 -0.2032)
						)
						(arc
							(start -0.3048 0.2032)
							(mid -0.275042 0.275042)
							(end -0.2032 0.3048)
						)
						(arc
							(start 0.2032 0.3048)
							(mid 0.275042 0.275042)
							(end 0.3048 0.2032)
						)
					)
					(width 0)
					(fill yes)
				)
			)
		)
	)
	(footprint ""
		(layer "F.Cu")
		(at 265.049 -20.447 -90)
		(property "Reference" "PC58"
			(at 0 0 270)
			(layer "F.SilkS")
			(hide yes)
			(effects
				(font
					(size 1.27 1.27)
				)
			)
		)
		(property "Value" "SC100U6D3V6MX-GP"
			(at -0.0762 -5.1308 270)
			(unlocked yes)
			(layer "F.Fab")
			(hide yes)
			(effects
				(font
					(size 1.016 1.016)
					(thickness 0.1524)
				)
			)
		)
		(property "Device Type" "C1206H71"
			(at -0.127 -6.6548 270)
			(unlocked yes)
			(layer "F.Fab")
			(hide yes)
			(effects
				(font
					(size 1.016 1.016)
					(thickness 0.1524)
				)
			)
		)
		(duplicate_pad_numbers_are_jumpers no)
		(fp_line
			(start -1.016 2.2352)
			(end -1.016 0.8382)
			(stroke
				(width 0.1524)
				(type default)
			)
			(layer "F.SilkS")
		)
		(fp_line
			(start 1.016 2.2352)
			(end -1.016 2.2352)
			(stroke
				(width 0.1524)
				(type default)
			)
			(layer "F.SilkS")
		)
		(fp_line
			(start 1.016 0.8382)
			(end 1.016 2.2352)
			(stroke
				(width 0.1524)
				(type default)
			)
			(layer "F.SilkS")
		)
		(fp_line
			(start -1.016 -0.8382)
			(end -1.016 -2.2352)
			(stroke
				(width 0.1524)
				(type default)
			)
			(layer "F.SilkS")
		)
		(fp_line
			(start -1.016 -2.2352)
			(end 1.016 -2.2352)
			(stroke
				(width 0.1524)
				(type default)
			)
			(layer "F.SilkS")
		)
		(fp_line
			(start 1.016 -2.2352)
			(end 1.016 -0.8382)
			(stroke
				(width 0.1524)
				(type default)
			)
			(layer "F.SilkS")
		)
		(fp_rect
			(start -1.0922 2.3114)
			(end 1.0922 -2.3114)
			(stroke
				(width 0)
				(type default)
			)
			(fill no)
			(layer "F.CrtYd")
		)
		(fp_poly
			(pts
				(xy 1.0922 -2.3114) (xy 1.0922 2.3114) (xy -1.0922 2.3114) (xy -1.0922 -2.3114)
			)
			(stroke
				(width 0)
				(type default)
			)
			(fill no)
			(layer "F.Fab")
		)
		(pad "1" smd rect
			(at 0 -1.397 270)
			(size 1.651 1.27)
			(layers "F.Cu" "F.Mask" "F.Paste")
			(net "P1V8_STBY")
		)
		(pad "2" smd rect
			(at 0 1.397 270)
			(size 1.651 1.27)
			(layers "F.Cu" "F.Mask" "F.Paste")
			(net "GND")
		)
	)
)
